(kicad_pcb
	(version 20260206)
	(generator "pcbnew")
	(generator_version "10.0")
	(general
		(thickness 1.6)
		(legacy_teardrops no)
	)
	(paper "A4")
	(title_block
		(title "03242023_DA0F0TMBIJ0_F0T_Motherboard_J_brd_V01_OCP.brd")
		(comment 1 "Grand Teton / footprints 2440-2445 of 6105")
	)
	(layers
		(0 "F.Cu" signal "TOP")
		(4 "In1.Cu" signal "GND")
		(6 "In2.Cu" signal "IN1")
		(8 "In3.Cu" signal "GND1")
		(10 "In4.Cu" signal "IN2")
		(12 "In5.Cu" signal "GND2")
		(14 "In6.Cu" signal "IN3")
		(16 "In7.Cu" signal "GND3")
		(18 "In8.Cu" signal "VCC")
		(20 "In9.Cu" signal "VCC1")
		(22 "In10.Cu" signal "GND4")
		(24 "In11.Cu" signal "IN4")
		(26 "In12.Cu" signal "GND5")
		(28 "In13.Cu" signal "IN5")
		(30 "In14.Cu" signal "GND6")
		(32 "In15.Cu" signal "IN6")
		(34 "In16.Cu" signal "GND7")
		(2 "B.Cu" signal "BOTTOM")
		(9 "F.Adhes" user "F.Adhesive")
		(11 "B.Adhes" user "B.Adhesive")
		(13 "F.Paste" user "Package Geometry/Pastemask Top")
		(15 "B.Paste" user "Package Geometry/Pastemask Bottom")
		(5 "F.SilkS" user "Ref Des/Silkscreen Top")
		(7 "B.SilkS" user "Ref Des/Silkscreen Bottom")
		(1 "F.Mask" user "Board Geometry/Soldermask Top")
		(3 "B.Mask" user "Board Geometry/Soldermask Bottom")
		(17 "Dwgs.User" user "User.Drawings")
		(19 "Cmts.User" user "User.Comments")
		(21 "Eco1.User" user "User.Eco1")
		(23 "Eco2.User" user "User.Eco2")
		(25 "Edge.Cuts" user "Board Geometry/Outline")
		(27 "Margin" user)
		(31 "F.CrtYd" user "Package Geometry/Place Bound Top")
		(29 "B.CrtYd" user "Package Geometry/Place Bound Bottom")
		(35 "F.Fab" user "Ref Des/Assembly Top")
		(33 "B.Fab" user "Ref Des/Assembly Bottom")
	)
	(footprint ""
		(layer "F.Cu")
		(at 77.982826 -347.481398 -90)
		(property "Reference" "PC1363"
			(at 0 0 270)
			(layer "F.SilkS")
			(hide yes)
			(effects
				(font
					(size 1.27 1.27)
				)
			)
		)
		(property "Value" ""
			(at 0 0 270)
			(layer "F.Fab")
			(effects
				(font
					(size 1.27 1.27)
				)
			)
		)
		(duplicate_pad_numbers_are_jumpers no)
		(fp_line
			(start -0.7874 0.4064)
			(end -0.7874 -0.4064)
			(stroke
				(width 0.1524)
				(type default)
			)
			(layer "F.SilkS")
		)
		(fp_line
			(start 0.7874 0.4064)
			(end -0.7874 0.4064)
			(stroke
				(width 0.1524)
				(type default)
			)
			(layer "F.SilkS")
		)
		(fp_line
			(start -0.7874 -0.4064)
			(end 0.7874 -0.4064)
			(stroke
				(width 0.1524)
				(type default)
			)
			(layer "F.SilkS")
		)
		(fp_line
			(start 0.7874 -0.4064)
			(end 0.7874 0.4064)
			(stroke
				(width 0.1524)
				(type default)
			)
			(layer "F.SilkS")
		)
		(fp_line
			(start -0.67945 0.3048)
			(end -0.67945 -0.305054)
			(stroke
				(width 0.1)
				(type default)
			)
			(layer "F.Fab")
		)
		(fp_line
			(start -0.12065 0.3048)
			(end -0.67945 0.3048)
			(stroke
				(width 0.1)
				(type default)
			)
			(layer "F.Fab")
		)
		(fp_line
			(start 0.120396 0.3048)
			(end 0.120396 0.2794)
			(stroke
				(width 0.1)
				(type default)
			)
			(layer "F.Fab")
		)
		(fp_line
			(start 0.67945 0.3048)
			(end 0.120396 0.3048)
			(stroke
				(width 0.1)
				(type default)
			)
			(layer "F.Fab")
		)
		(fp_line
			(start -0.12065 0.2794)
			(end -0.12065 0.3048)
			(stroke
				(width 0.1)
				(type default)
			)
			(layer "F.Fab")
		)
		(fp_line
			(start 0.120396 0.2794)
			(end -0.12065 0.2794)
			(stroke
				(width 0.1)
				(type default)
			)
			(layer "F.Fab")
		)
		(fp_line
			(start -0.12065 -0.2794)
			(end 0.12065 -0.2794)
			(stroke
				(width 0.1)
				(type default)
			)
			(layer "F.Fab")
		)
		(fp_line
			(start 0.12065 -0.2794)
			(end 0.12065 -0.3048)
			(stroke
				(width 0.1)
				(type default)
			)
			(layer "F.Fab")
		)
		(fp_line
			(start 0.12065 -0.3048)
			(end 0.67945 -0.3048)
			(stroke
				(width 0.1)
				(type default)
			)
			(layer "F.Fab")
		)
		(fp_line
			(start 0.67945 -0.3048)
			(end 0.67945 0.3048)
			(stroke
				(width 0.1)
				(type default)
			)
			(layer "F.Fab")
		)
		(fp_line
			(start -0.67945 -0.305054)
			(end -0.12065 -0.305054)
			(stroke
				(width 0.1)
				(type default)
			)
			(layer "F.Fab")
		)
		(fp_line
			(start -0.12065 -0.305054)
			(end -0.12065 -0.2794)
			(stroke
				(width 0.1)
				(type default)
			)
			(layer "F.Fab")
		)
		(pad "1" smd circle
			(at -0.40005 0 270)
			(size 0 0)
			(layers "F.Cu" "F.Mask" "F.Paste")
			(net "GND")
		)
		(pad "2" smd circle
			(at 0.40005 0 270)
			(size 0 0)
			(layers "F.Cu" "F.Mask" "F.Paste")
			(net "PVCCIN_CPU1_VREF")
		)
	)
	(footprint ""
		(layer "F.Cu")
		(at 105.2957 -256.6543 -90)
		(property "Reference" "C445"
			(at 0 0 270)
			(layer "F.SilkS")
			(hide yes)
			(effects
				(font
					(size 1.27 1.27)
				)
			)
		)
		(property "Value" ""
			(at 0 0 270)
			(layer "F.Fab")
			(effects
				(font
					(size 1.27 1.27)
				)
			)
		)
		(duplicate_pad_numbers_are_jumpers no)
		(fp_line
			(start -0.7874 0.4064)
			(end -0.7874 -0.4064)
			(stroke
				(width 0.1524)
				(type default)
			)
			(layer "F.SilkS")
		)
		(fp_line
			(start 0.7874 0.4064)
			(end -0.7874 0.4064)
			(stroke
				(width 0.1524)
				(type default)
			)
			(layer "F.SilkS")
		)
		(fp_line
			(start -0.7874 -0.4064)
			(end 0.7874 -0.4064)
			(stroke
				(width 0.1524)
				(type default)
			)
			(layer "F.SilkS")
		)
		(fp_line
			(start 0.7874 -0.4064)
			(end 0.7874 0.4064)
			(stroke
				(width 0.1524)
				(type default)
			)
			(layer "F.SilkS")
		)
		(fp_line
			(start -0.67945 0.3048)
			(end -0.67945 -0.305054)
			(stroke
				(width 0.1)
				(type default)
			)
			(layer "F.Fab")
		)
		(fp_line
			(start -0.12065 0.3048)
			(end -0.67945 0.3048)
			(stroke
				(width 0.1)
				(type default)
			)
			(layer "F.Fab")
		)
		(fp_line
			(start 0.120396 0.3048)
			(end 0.120396 0.2794)
			(stroke
				(width 0.1)
				(type default)
			)
			(layer "F.Fab")
		)
		(fp_line
			(start 0.67945 0.3048)
			(end 0.120396 0.3048)
			(stroke
				(width 0.1)
				(type default)
			)
			(layer "F.Fab")
		)
		(fp_line
			(start -0.12065 0.2794)
			(end -0.12065 0.3048)
			(stroke
				(width 0.1)
				(type default)
			)
			(layer "F.Fab")
		)
		(fp_line
			(start 0.120396 0.2794)
			(end -0.12065 0.2794)
			(stroke
				(width 0.1)
				(type default)
			)
			(layer "F.Fab")
		)
		(fp_line
			(start -0.12065 -0.2794)
			(end 0.12065 -0.2794)
			(stroke
				(width 0.1)
				(type default)
			)
			(layer "F.Fab")
		)
		(fp_line
			(start 0.12065 -0.2794)
			(end 0.12065 -0.3048)
			(stroke
				(width 0.1)
				(type default)
			)
			(layer "F.Fab")
		)
		(fp_line
			(start 0.12065 -0.3048)
			(end 0.67945 -0.3048)
			(stroke
				(width 0.1)
				(type default)
			)
			(layer "F.Fab")
		)
		(fp_line
			(start 0.67945 -0.3048)
			(end 0.67945 0.3048)
			(stroke
				(width 0.1)
				(type default)
			)
			(layer "F.Fab")
		)
		(fp_line
			(start -0.67945 -0.305054)
			(end -0.12065 -0.305054)
			(stroke
				(width 0.1)
				(type default)
			)
			(layer "F.Fab")
		)
		(fp_line
			(start -0.12065 -0.305054)
			(end -0.12065 -0.2794)
			(stroke
				(width 0.1)
				(type default)
			)
			(layer "F.Fab")
		)
		(pad "1" smd circle
			(at -0.40005 0 270)
			(size 0 0)
			(layers "F.Cu" "F.Mask" "F.Paste")
			(net "PVCCFA_EHV_CPU1")
		)
		(pad "2" smd circle
			(at 0.40005 0 270)
			(size 0 0)
			(layers "F.Cu" "F.Mask" "F.Paste")
			(net "GND")
		)
	)
	(footprint ""
		(layer "F.Cu")
		(at 120.333262 -16.91005)
		(property "Reference" "R4201"
			(at 0 0 0)
			(layer "F.SilkS")
			(hide yes)
			(effects
				(font
					(size 1.27 1.27)
				)
			)
		)
		(property "Value" ""
			(at 0 0 0)
			(layer "F.Fab")
			(effects
				(font
					(size 1.27 1.27)
				)
			)
		)
		(duplicate_pad_numbers_are_jumpers no)
		(fp_line
			(start -0.7874 -0.4064)
			(end 0.7874 -0.4064)
			(stroke
				(width 0.1524)
				(type default)
			)
			(layer "F.SilkS")
		)
		(fp_line
			(start -0.7874 0.4064)
			(end -0.7874 -0.4064)
			(stroke
				(width 0.1524)
				(type default)
			)
			(layer "F.SilkS")
		)
		(fp_line
			(start 0.7874 -0.4064)
			(end 0.7874 0.4064)
			(stroke
				(width 0.1524)
				(type default)
			)
			(layer "F.SilkS")
		)
		(fp_line
			(start 0.7874 0.4064)
			(end -0.7874 0.4064)
			(stroke
				(width 0.1524)
				(type default)
			)
			(layer "F.SilkS")
		)
		(fp_line
			(start -0.67945 -0.305054)
			(end -0.12065 -0.305054)
			(stroke
				(width 0.1)
				(type default)
			)
			(layer "F.Fab")
		)
		(fp_line
			(start -0.67945 0.3048)
			(end -0.67945 -0.305054)
			(stroke
				(width 0.1)
				(type default)
			)
			(layer "F.Fab")
		)
		(fp_line
			(start -0.12065 -0.305054)
			(end -0.12065 -0.2794)
			(stroke
				(width 0.1)
				(type default)
			)
			(layer "F.Fab")
		)
		(fp_line
			(start -0.12065 -0.2794)
			(end 0.12065 -0.2794)
			(stroke
				(width 0.1)
				(type default)
			)
			(layer "F.Fab")
		)
		(fp_line
			(start -0.12065 0.2794)
			(end -0.12065 0.3048)
			(stroke
				(width 0.1)
				(type default)
			)
			(layer "F.Fab")
		)
		(fp_line
			(start -0.12065 0.3048)
			(end -0.67945 0.3048)
			(stroke
				(width 0.1)
				(type default)
			)
			(layer "F.Fab")
		)
		(fp_line
			(start 0.120396 0.2794)
			(end -0.12065 0.2794)
			(stroke
				(width 0.1)
				(type default)
			)
			(layer "F.Fab")
		)
		(fp_line
			(start 0.120396 0.3048)
			(end 0.120396 0.2794)
			(stroke
				(width 0.1)
				(type default)
			)
			(layer "F.Fab")
		)
		(fp_line
			(start 0.12065 -0.3048)
			(end 0.67945 -0.3048)
			(stroke
				(width 0.1)
				(type default)
			)
			(layer "F.Fab")
		)
		(fp_line
			(start 0.12065 -0.2794)
			(end 0.12065 -0.3048)
			(stroke
				(width 0.1)
				(type default)
			)
			(layer "F.Fab")
		)
		(fp_line
			(start 0.67945 -0.3048)
			(end 0.67945 0.3048)
			(stroke
				(width 0.1)
				(type default)
			)
			(layer "F.Fab")
		)
		(fp_line
			(start 0.67945 0.3048)
			(end 0.120396 0.3048)
			(stroke
				(width 0.1)
				(type default)
			)
			(layer "F.Fab")
		)
		(pad "1" smd circle
			(at -0.40005 0)
			(size 0 0)
			(layers "F.Cu" "F.Mask" "F.Paste")
			(net "U273_3_ADD0")
		)
		(pad "2" smd circle
			(at 0.40005 0)
			(size 0 0)
			(layers "F.Cu" "F.Mask" "F.Paste")
			(net "GND")
		)
	)
	(footprint ""
		(layer "F.Cu")
		(at 118.954042 -66.693034 90)
		(property "Reference" "R929"
			(at 0 0 90)
			(layer "F.SilkS")
			(hide yes)
			(effects
				(font
					(size 1.27 1.27)
				)
			)
		)
		(property "Value" ""
			(at 0 0 90)
			(layer "F.Fab")
			(effects
				(font
					(size 1.27 1.27)
				)
			)
		)
		(duplicate_pad_numbers_are_jumpers no)
		(fp_line
			(start 0.7874 -0.4064)
			(end 0.7874 0.4064)
			(stroke
				(width 0.1524)
				(type default)
			)
			(layer "F.SilkS")
		)
		(fp_line
			(start -0.7874 -0.4064)
			(end 0.7874 -0.4064)
			(stroke
				(width 0.1524)
				(type default)
			)
			(layer "F.SilkS")
		)
		(fp_line
			(start 0.7874 0.4064)
			(end -0.7874 0.4064)
			(stroke
				(width 0.1524)
				(type default)
			)
			(layer "F.SilkS")
		)
		(fp_line
			(start -0.7874 0.4064)
			(end -0.7874 -0.4064)
			(stroke
				(width 0.1524)
				(type default)
			)
			(layer "F.SilkS")
		)
		(fp_line
			(start -0.12065 -0.305054)
			(end -0.12065 -0.2794)
			(stroke
				(width 0.1)
				(type default)
			)
			(layer "F.Fab")
		)
		(fp_line
			(start -0.67945 -0.305054)
			(end -0.12065 -0.305054)
			(stroke
				(width 0.1)
				(type default)
			)
			(layer "F.Fab")
		)
		(fp_line
			(start 0.67945 -0.3048)
			(end 0.67945 0.3048)
			(stroke
				(width 0.1)
				(type default)
			)
			(layer "F.Fab")
		)
		(fp_line
			(start 0.12065 -0.3048)
			(end 0.67945 -0.3048)
			(stroke
				(width 0.1)
				(type default)
			)
			(layer "F.Fab")
		)
		(fp_line
			(start 0.12065 -0.2794)
			(end 0.12065 -0.3048)
			(stroke
				(width 0.1)
				(type default)
			)
			(layer "F.Fab")
		)
		(fp_line
			(start -0.12065 -0.2794)
			(end 0.12065 -0.2794)
			(stroke
				(width 0.1)
				(type default)
			)
			(layer "F.Fab")
		)
		(fp_line
			(start 0.120396 0.2794)
			(end -0.12065 0.2794)
			(stroke
				(width 0.1)
				(type default)
			)
			(layer "F.Fab")
		)
		(fp_line
			(start -0.12065 0.2794)
			(end -0.12065 0.3048)
			(stroke
				(width 0.1)
				(type default)
			)
			(layer "F.Fab")
		)
		(fp_line
			(start 0.67945 0.3048)
			(end 0.120396 0.3048)
			(stroke
				(width 0.1)
				(type default)
			)
			(layer "F.Fab")
		)
		(fp_line
			(start 0.120396 0.3048)
			(end 0.120396 0.2794)
			(stroke
				(width 0.1)
				(type default)
			)
			(layer "F.Fab")
		)
		(fp_line
			(start -0.12065 0.3048)
			(end -0.67945 0.3048)
			(stroke
				(width 0.1)
				(type default)
			)
			(layer "F.Fab")
		)
		(fp_line
			(start -0.67945 0.3048)
			(end -0.67945 -0.305054)
			(stroke
				(width 0.1)
				(type default)
			)
			(layer "F.Fab")
		)
		(pad "1" smd circle
			(at -0.40005 0 90)
			(size 0 0)
			(layers "F.Cu" "F.Mask" "F.Paste")
			(net "P3V3_AUX")
		)
		(pad "2" smd circle
			(at 0.40005 0 90)
			(size 0 0)
			(layers "F.Cu" "F.Mask" "F.Paste")
			(net "JTAG_BMC_PLD_TMS")
		)
	)
	(footprint ""
		(layer "F.Cu")
		(at 153.944066 -31.341568 -90)
		(property "Reference" "C2317"
			(at 0 0 270)
			(layer "F.SilkS")
			(hide yes)
			(effects
				(font
					(size 1.27 1.27)
				)
			)
		)
		(property "Value" ""
			(at 0 0 270)
			(layer "F.Fab")
			(effects
				(font
					(size 1.27 1.27)
				)
			)
		)
		(duplicate_pad_numbers_are_jumpers no)
		(fp_line
			(start -0.7874 0.4064)
			(end -0.7874 -0.4064)
			(stroke
				(width 0.1524)
				(type default)
			)
			(layer "F.SilkS")
		)
		(fp_line
			(start 0.7874 0.4064)
			(end -0.7874 0.4064)
			(stroke
				(width 0.1524)
				(type default)
			)
			(layer "F.SilkS")
		)
		(fp_line
			(start -0.7874 -0.4064)
			(end 0.7874 -0.4064)
			(stroke
				(width 0.1524)
				(type default)
			)
			(layer "F.SilkS")
		)
		(fp_line
			(start 0.7874 -0.4064)
			(end 0.7874 0.4064)
			(stroke
				(width 0.1524)
				(type default)
			)
			(layer "F.SilkS")
		)
		(fp_line
			(start -0.67945 0.3048)
			(end -0.67945 -0.305054)
			(stroke
				(width 0.1)
				(type default)
			)
			(layer "F.Fab")
		)
		(fp_line
			(start -0.12065 0.3048)
			(end -0.67945 0.3048)
			(stroke
				(width 0.1)
				(type default)
			)
			(layer "F.Fab")
		)
		(fp_line
			(start 0.120396 0.3048)
			(end 0.120396 0.2794)
			(stroke
				(width 0.1)
				(type default)
			)
			(layer "F.Fab")
		)
		(fp_line
			(start 0.67945 0.3048)
			(end 0.120396 0.3048)
			(stroke
				(width 0.1)
				(type default)
			)
			(layer "F.Fab")
		)
		(fp_line
			(start -0.12065 0.2794)
			(end -0.12065 0.3048)
			(stroke
				(width 0.1)
				(type default)
			)
			(layer "F.Fab")
		)
		(fp_line
			(start 0.120396 0.2794)
			(end -0.12065 0.2794)
			(stroke
				(width 0.1)
				(type default)
			)
			(layer "F.Fab")
		)
		(fp_line
			(start -0.12065 -0.2794)
			(end 0.12065 -0.2794)
			(stroke
				(width 0.1)
				(type default)
			)
			(layer "F.Fab")
		)
		(fp_line
			(start 0.12065 -0.2794)
			(end 0.12065 -0.3048)
			(stroke
				(width 0.1)
				(type default)
			)
			(layer "F.Fab")
		)
		(fp_line
			(start 0.12065 -0.3048)
			(end 0.67945 -0.3048)
			(stroke
				(width 0.1)
				(type default)
			)
			(layer "F.Fab")
		)
		(fp_line
			(start 0.67945 -0.3048)
			(end 0.67945 0.3048)
			(stroke
				(width 0.1)
				(type default)
			)
			(layer "F.Fab")
		)
		(fp_line
			(start -0.67945 -0.305054)
			(end -0.12065 -0.305054)
			(stroke
				(width 0.1)
				(type default)
			)
			(layer "F.Fab")
		)
		(fp_line
			(start -0.12065 -0.305054)
			(end -0.12065 -0.2794)
			(stroke
				(width 0.1)
				(type default)
			)
			(layer "F.Fab")
		)
		(pad "1" smd circle
			(at -0.40005 0 270)
			(size 0 0)
			(layers "F.Cu" "F.Mask" "F.Paste")
			(net "RST_USB_HUB_2_R_N")
		)
		(pad "2" smd circle
			(at 0.40005 0 270)
			(size 0 0)
			(layers "F.Cu" "F.Mask" "F.Paste")
			(net "GND")
		)
	)
	(footprint ""
		(layer "F.Cu")
		(at 174.04588 -130.266948 90)
		(property "Reference" "R1399"
			(at 0 0 90)
			(layer "F.SilkS")
			(hide yes)
			(effects
				(font
					(size 1.27 1.27)
				)
			)
		)
		(property "Value" ""
			(at 0 0 90)
			(layer "F.Fab")
			(effects
				(font
					(size 1.27 1.27)
				)
			)
		)
		(duplicate_pad_numbers_are_jumpers no)
		(fp_line
			(start 0.7874 -0.4064)
			(end 0.7874 0.4064)
			(stroke
				(width 0.1524)
				(type default)
			)
			(layer "F.SilkS")
		)
		(fp_line
			(start -0.7874 -0.4064)
			(end 0.7874 -0.4064)
			(stroke
				(width 0.1524)
				(type default)
			)
			(layer "F.SilkS")
		)
		(fp_line
			(start 0.7874 0.4064)
			(end -0.7874 0.4064)
			(stroke
				(width 0.1524)
				(type default)
			)
			(layer "F.SilkS")
		)
		(fp_line
			(start -0.7874 0.4064)
			(end -0.7874 -0.4064)
			(stroke
				(width 0.1524)
				(type default)
			)
			(layer "F.SilkS")
		)
		(fp_line
			(start -0.12065 -0.305054)
			(end -0.12065 -0.2794)
			(stroke
				(width 0.1)
				(type default)
			)
			(layer "F.Fab")
		)
		(fp_line
			(start -0.67945 -0.305054)
			(end -0.12065 -0.305054)
			(stroke
				(width 0.1)
				(type default)
			)
			(layer "F.Fab")
		)
		(fp_line
			(start 0.67945 -0.3048)
			(end 0.67945 0.3048)
			(stroke
				(width 0.1)
				(type default)
			)
			(layer "F.Fab")
		)
		(fp_line
			(start 0.12065 -0.3048)
			(end 0.67945 -0.3048)
			(stroke
				(width 0.1)
				(type default)
			)
			(layer "F.Fab")
		)
		(fp_line
			(start 0.12065 -0.2794)
			(end 0.12065 -0.3048)
			(stroke
				(width 0.1)
				(type default)
			)
			(layer "F.Fab")
		)
		(fp_line
			(start -0.12065 -0.2794)
			(end 0.12065 -0.2794)
			(stroke
				(width 0.1)
				(type default)
			)
			(layer "F.Fab")
		)
		(fp_line
			(start 0.120396 0.2794)
			(end -0.12065 0.2794)
			(stroke
				(width 0.1)
				(type default)
			)
			(layer "F.Fab")
		)
		(fp_line
			(start -0.12065 0.2794)
			(end -0.12065 0.3048)
			(stroke
				(width 0.1)
				(type default)
			)
			(layer "F.Fab")
		)
		(fp_line
			(start 0.67945 0.3048)
			(end 0.120396 0.3048)
			(stroke
				(width 0.1)
				(type default)
			)
			(layer "F.Fab")
		)
		(fp_line
			(start 0.120396 0.3048)
			(end 0.120396 0.2794)
			(stroke
				(width 0.1)
				(type default)
			)
			(layer "F.Fab")
		)
		(fp_line
			(start -0.12065 0.3048)
			(end -0.67945 0.3048)
			(stroke
				(width 0.1)
				(type default)
			)
			(layer "F.Fab")
		)
		(fp_line
			(start -0.67945 0.3048)
			(end -0.67945 -0.305054)
			(stroke
				(width 0.1)
				(type default)
			)
			(layer "F.Fab")
		)
		(pad "1" smd circle
			(at -0.40005 0 90)
			(size 0 0)
			(layers "F.Cu" "F.Mask" "F.Paste")
			(net "FM_PFR_DSW_PWROK_N")
		)
		(pad "2" smd circle
			(at 0.40005 0 90)
			(size 0 0)
			(layers "F.Cu" "F.Mask" "F.Paste")
			(net "P3V3_AUX")
		)
	)
)
